(kicad_pcb
	(version 20260206)
	(generator "pcbnew")
	(generator_version "10.0")
	(general
		(thickness 1.6)
		(legacy_teardrops no)
	)
	(paper "A4")
	(title_block
		(title "04192023_DAF0TMB3IC0_F0TG_MB_C_brd_V02_OCP.brd")
		(comment 1 "Grand Teton / footprints 6212-6219 of 8354")
	)
	(layers
		(0 "F.Cu" signal "TOP")
		(4 "In1.Cu" signal "GND")
		(6 "In2.Cu" signal "IN1")
		(8 "In3.Cu" signal "GND1")
		(10 "In4.Cu" signal "IN2")
		(12 "In5.Cu" signal "GND2")
		(14 "In6.Cu" signal "IN3")
		(16 "In7.Cu" signal "GND3")
		(18 "In8.Cu" signal "VCC")
		(20 "In9.Cu" signal "VCC1")
		(22 "In10.Cu" signal "GND4")
		(24 "In11.Cu" signal "IN4")
		(26 "In12.Cu" signal "GND5")
		(28 "In13.Cu" signal "IN5")
		(30 "In14.Cu" signal "GND6")
		(32 "In15.Cu" signal "IN6")
		(34 "In16.Cu" signal "GND7")
		(2 "B.Cu" signal "BOTTOM")
		(9 "F.Adhes" user "F.Adhesive")
		(11 "B.Adhes" user "B.Adhesive")
		(13 "F.Paste" user "Package Geometry/Pastemask Top")
		(15 "B.Paste" user "Package Geometry/Pastemask Bottom")
		(5 "F.SilkS" user "Ref Des/Silkscreen Top")
		(7 "B.SilkS" user "Ref Des/Silkscreen Bottom")
		(1 "F.Mask" user "Board Geometry/Soldermask Top")
		(3 "B.Mask" user "Board Geometry/Soldermask Bottom")
		(17 "Dwgs.User" user "User.Drawings")
		(19 "Cmts.User" user "User.Comments")
		(21 "Eco1.User" user "User.Eco1")
		(23 "Eco2.User" user "User.Eco2")
		(25 "Edge.Cuts" user "Board Geometry/Outline")
		(27 "Margin" user)
		(31 "F.CrtYd" user "Package Geometry/Place Bound Top")
		(29 "B.CrtYd" user "Package Geometry/Place Bound Bottom")
		(35 "F.Fab" user "Ref Des/Assembly Top")
		(33 "B.Fab" user "Ref Des/Assembly Bottom")
	)
	(footprint ""
		(layer "B.Cu")
		(at 29.252164 -192.66027)
		(property "Reference" "C183"
			(at 0 0 0)
			(layer "B.SilkS")
			(hide yes)
			(effects
				(font
					(size 1.27 1.27)
				)
				(justify mirror)
			)
		)
		(property "Value" ""
			(at 0 0 0)
			(layer "B.Fab")
			(effects
				(font
					(size 1.27 1.27)
				)
				(justify mirror)
			)
		)
		(duplicate_pad_numbers_are_jumpers no)
		(fp_line
			(start -1.524 -0.762)
			(end -1.524 0.762)
			(stroke
				(width 0.1524)
				(type default)
			)
			(layer "B.SilkS")
		)
		(fp_line
			(start -1.524 0.762)
			(end 1.524 0.762)
			(stroke
				(width 0.1524)
				(type default)
			)
			(layer "B.SilkS")
		)
		(fp_line
			(start 1.524 -0.762)
			(end -1.524 -0.762)
			(stroke
				(width 0.1524)
				(type default)
			)
			(layer "B.SilkS")
		)
		(fp_line
			(start 1.524 0.762)
			(end 1.524 -0.762)
			(stroke
				(width 0.1524)
				(type default)
			)
			(layer "B.SilkS")
		)
		(fp_line
			(start -1.1049 -0.724916)
			(end 1.1049 -0.724916)
			(stroke
				(width 0.1)
				(type default)
			)
			(layer "B.Fab")
		)
		(fp_line
			(start -1.1049 0.724916)
			(end -1.1049 -0.724916)
			(stroke
				(width 0.1)
				(type default)
			)
			(layer "B.Fab")
		)
		(fp_line
			(start 1.1049 -0.724916)
			(end 1.1049 0.724916)
			(stroke
				(width 0.1)
				(type default)
			)
			(layer "B.Fab")
		)
		(fp_line
			(start 1.1049 0.724916)
			(end -1.1049 0.724916)
			(stroke
				(width 0.1)
				(type default)
			)
			(layer "B.Fab")
		)
		(pad "1" smd rect
			(at 0.889 0)
			(size 1.016 1.27)
			(layers "B.Cu" "B.Mask" "B.Paste")
			(net "P12V_MEM_CPU1")
		)
		(pad "2" smd rect
			(at -0.889 0)
			(size 1.016 1.27)
			(layers "B.Cu" "B.Mask" "B.Paste")
			(net "GND")
		)
	)
	(footprint ""
		(layer "B.Cu")
		(at 305.239928 -338.082128 -90)
		(property "Reference" "PC127_4"
			(at 0 0 90)
			(layer "B.SilkS")
			(hide yes)
			(effects
				(font
					(size 1.27 1.27)
				)
				(justify mirror)
			)
		)
		(property "Value" ""
			(at 0 0 90)
			(layer "B.Fab")
			(effects
				(font
					(size 1.27 1.27)
				)
				(justify mirror)
			)
		)
		(duplicate_pad_numbers_are_jumpers no)
		(fp_line
			(start -1.524 0.762)
			(end 1.524 0.762)
			(stroke
				(width 0.1524)
				(type default)
			)
			(layer "B.SilkS")
		)
		(fp_line
			(start 1.524 0.762)
			(end 1.524 -0.762)
			(stroke
				(width 0.1524)
				(type default)
			)
			(layer "B.SilkS")
		)
		(fp_line
			(start -1.524 -0.762)
			(end -1.524 0.762)
			(stroke
				(width 0.1524)
				(type default)
			)
			(layer "B.SilkS")
		)
		(fp_line
			(start 1.524 -0.762)
			(end -1.524 -0.762)
			(stroke
				(width 0.1524)
				(type default)
			)
			(layer "B.SilkS")
		)
		(fp_line
			(start -1.1049 0.724916)
			(end -1.1049 -0.724916)
			(stroke
				(width 0.1)
				(type default)
			)
			(layer "B.Fab")
		)
		(fp_line
			(start 1.1049 0.724916)
			(end -1.1049 0.724916)
			(stroke
				(width 0.1)
				(type default)
			)
			(layer "B.Fab")
		)
		(fp_line
			(start -1.1049 -0.724916)
			(end 1.1049 -0.724916)
			(stroke
				(width 0.1)
				(type default)
			)
			(layer "B.Fab")
		)
		(fp_line
			(start 1.1049 -0.724916)
			(end 1.1049 0.724916)
			(stroke
				(width 0.1)
				(type default)
			)
			(layer "B.Fab")
		)
		(pad "1" smd rect
			(at 0.889 0 270)
			(size 1.016 1.27)
			(layers "B.Cu" "B.Mask" "B.Paste")
			(net "PVDDCR_CPU1_P0")
		)
		(pad "2" smd rect
			(at -0.889 0 270)
			(size 1.016 1.27)
			(layers "B.Cu" "B.Mask" "B.Paste")
			(net "GND")
		)
	)
	(footprint ""
		(layer "B.Cu")
		(at 236.62513 -48.104044)
		(property "Reference" "C1283"
			(at 0 0 0)
			(layer "B.SilkS")
			(hide yes)
			(effects
				(font
					(size 1.27 1.27)
				)
				(justify mirror)
			)
		)
		(property "Value" ""
			(at 0 0 0)
			(layer "B.Fab")
			(effects
				(font
					(size 1.27 1.27)
				)
				(justify mirror)
			)
		)
		(duplicate_pad_numbers_are_jumpers no)
		(fp_line
			(start -0.7874 -0.4064)
			(end -0.7874 0.4064)
			(stroke
				(width 0.1524)
				(type default)
			)
			(layer "B.SilkS")
		)
		(fp_line
			(start -0.7874 0.4064)
			(end 0.7874 0.4064)
			(stroke
				(width 0.1524)
				(type default)
			)
			(layer "B.SilkS")
		)
		(fp_line
			(start 0.7874 -0.4064)
			(end -0.7874 -0.4064)
			(stroke
				(width 0.1524)
				(type default)
			)
			(layer "B.SilkS")
		)
		(fp_line
			(start 0.7874 0.4064)
			(end 0.7874 -0.4064)
			(stroke
				(width 0.1524)
				(type default)
			)
			(layer "B.SilkS")
		)
		(fp_line
			(start -0.67945 -0.3048)
			(end -0.67945 0.3048)
			(stroke
				(width 0.1)
				(type default)
			)
			(layer "B.Fab")
		)
		(fp_line
			(start -0.67945 0.3048)
			(end -0.120396 0.3048)
			(stroke
				(width 0.1)
				(type default)
			)
			(layer "B.Fab")
		)
		(fp_line
			(start -0.12065 -0.3048)
			(end -0.67945 -0.3048)
			(stroke
				(width 0.1)
				(type default)
			)
			(layer "B.Fab")
		)
		(fp_line
			(start -0.12065 -0.2794)
			(end -0.12065 -0.3048)
			(stroke
				(width 0.1)
				(type default)
			)
			(layer "B.Fab")
		)
		(fp_line
			(start -0.120396 0.2794)
			(end 0.12065 0.2794)
			(stroke
				(width 0.1)
				(type default)
			)
			(layer "B.Fab")
		)
		(fp_line
			(start -0.120396 0.3048)
			(end -0.120396 0.2794)
			(stroke
				(width 0.1)
				(type default)
			)
			(layer "B.Fab")
		)
		(fp_line
			(start 0.12065 -0.305054)
			(end 0.12065 -0.2794)
			(stroke
				(width 0.1)
				(type default)
			)
			(layer "B.Fab")
		)
		(fp_line
			(start 0.12065 -0.2794)
			(end -0.12065 -0.2794)
			(stroke
				(width 0.1)
				(type default)
			)
			(layer "B.Fab")
		)
		(fp_line
			(start 0.12065 0.2794)
			(end 0.12065 0.3048)
			(stroke
				(width 0.1)
				(type default)
			)
			(layer "B.Fab")
		)
		(fp_line
			(start 0.12065 0.3048)
			(end 0.67945 0.3048)
			(stroke
				(width 0.1)
				(type default)
			)
			(layer "B.Fab")
		)
		(fp_line
			(start 0.67945 -0.305054)
			(end 0.12065 -0.305054)
			(stroke
				(width 0.1)
				(type default)
			)
			(layer "B.Fab")
		)
		(fp_line
			(start 0.67945 0.3048)
			(end 0.67945 -0.305054)
			(stroke
				(width 0.1)
				(type default)
			)
			(layer "B.Fab")
		)
		(pad "1" smd circle
			(at 0.40005 0 180)
			(size 0 0)
			(layers "B.Cu" "B.Mask" "B.Paste")
			(net "P3V3_E1S_0")
		)
		(pad "2" smd circle
			(at -0.40005 0 180)
			(size 0 0)
			(layers "B.Cu" "B.Mask" "B.Paste")
			(net "GND")
		)
	)
	(footprint ""
		(layer "B.Cu")
		(at 177.264822 -10.1473 -90)
		(property "Reference" "R2421"
			(at 0 0 90)
			(layer "B.SilkS")
			(hide yes)
			(effects
				(font
					(size 1.27 1.27)
				)
				(justify mirror)
			)
		)
		(property "Value" ""
			(at 0 0 90)
			(layer "B.Fab")
			(effects
				(font
					(size 1.27 1.27)
				)
				(justify mirror)
			)
		)
		(duplicate_pad_numbers_are_jumpers no)
		(fp_line
			(start -0.7874 0.4064)
			(end 0.7874 0.4064)
			(stroke
				(width 0.1524)
				(type default)
			)
			(layer "B.SilkS")
		)
		(fp_line
			(start 0.7874 0.4064)
			(end 0.7874 -0.4064)
			(stroke
				(width 0.1524)
				(type default)
			)
			(layer "B.SilkS")
		)
		(fp_line
			(start -0.7874 -0.4064)
			(end -0.7874 0.4064)
			(stroke
				(width 0.1524)
				(type default)
			)
			(layer "B.SilkS")
		)
		(fp_line
			(start 0.7874 -0.4064)
			(end -0.7874 -0.4064)
			(stroke
				(width 0.1524)
				(type default)
			)
			(layer "B.SilkS")
		)
		(fp_line
			(start -0.67945 0.3048)
			(end -0.120396 0.3048)
			(stroke
				(width 0.1)
				(type default)
			)
			(layer "B.Fab")
		)
		(fp_line
			(start -0.120396 0.3048)
			(end -0.120396 0.2794)
			(stroke
				(width 0.1)
				(type default)
			)
			(layer "B.Fab")
		)
		(fp_line
			(start 0.12065 0.3048)
			(end 0.67945 0.3048)
			(stroke
				(width 0.1)
				(type default)
			)
			(layer "B.Fab")
		)
		(fp_line
			(start 0.67945 0.3048)
			(end 0.67945 -0.305054)
			(stroke
				(width 0.1)
				(type default)
			)
			(layer "B.Fab")
		)
		(fp_line
			(start -0.120396 0.2794)
			(end 0.12065 0.2794)
			(stroke
				(width 0.1)
				(type default)
			)
			(layer "B.Fab")
		)
		(fp_line
			(start 0.12065 0.2794)
			(end 0.12065 0.3048)
			(stroke
				(width 0.1)
				(type default)
			)
			(layer "B.Fab")
		)
		(fp_line
			(start -0.12065 -0.2794)
			(end -0.12065 -0.3048)
			(stroke
				(width 0.1)
				(type default)
			)
			(layer "B.Fab")
		)
		(fp_line
			(start 0.12065 -0.2794)
			(end -0.12065 -0.2794)
			(stroke
				(width 0.1)
				(type default)
			)
			(layer "B.Fab")
		)
		(fp_line
			(start -0.67945 -0.3048)
			(end -0.67945 0.3048)
			(stroke
				(width 0.1)
				(type default)
			)
			(layer "B.Fab")
		)
		(fp_line
			(start -0.12065 -0.3048)
			(end -0.67945 -0.3048)
			(stroke
				(width 0.1)
				(type default)
			)
			(layer "B.Fab")
		)
		(fp_line
			(start 0.12065 -0.305054)
			(end 0.12065 -0.2794)
			(stroke
				(width 0.1)
				(type default)
			)
			(layer "B.Fab")
		)
		(fp_line
			(start 0.67945 -0.305054)
			(end 0.12065 -0.305054)
			(stroke
				(width 0.1)
				(type default)
			)
			(layer "B.Fab")
		)
		(pad "1" smd circle
			(at 0.40005 0 90)
			(size 0 0)
			(layers "B.Cu" "B.Mask" "B.Paste")
			(net "SMB_VR_SENSOR_3V3AUX_SCL")
		)
		(pad "2" smd circle
			(at -0.40005 0 90)
			(size 0 0)
			(layers "B.Cu" "B.Mask" "B.Paste")
			(net "SMB_VR_3V3AUX_SCL_R0")
		)
	)
	(footprint ""
		(layer "B.Cu")
		(at 240.411 -234.061 90)
		(property "Reference" "R1160"
			(at 0 0 90)
			(layer "B.SilkS")
			(hide yes)
			(effects
				(font
					(size 1.27 1.27)
				)
				(justify mirror)
			)
		)
		(property "Value" ""
			(at 0 0 90)
			(layer "B.Fab")
			(effects
				(font
					(size 1.27 1.27)
				)
				(justify mirror)
			)
		)
		(duplicate_pad_numbers_are_jumpers no)
		(fp_line
			(start 0.7874 -0.4064)
			(end -0.7874 -0.4064)
			(stroke
				(width 0.1524)
				(type default)
			)
			(layer "B.SilkS")
		)
		(fp_line
			(start -0.7874 -0.4064)
			(end -0.7874 0.4064)
			(stroke
				(width 0.1524)
				(type default)
			)
			(layer "B.SilkS")
		)
		(fp_line
			(start 0.7874 0.4064)
			(end 0.7874 -0.4064)
			(stroke
				(width 0.1524)
				(type default)
			)
			(layer "B.SilkS")
		)
		(fp_line
			(start -0.7874 0.4064)
			(end 0.7874 0.4064)
			(stroke
				(width 0.1524)
				(type default)
			)
			(layer "B.SilkS")
		)
		(fp_line
			(start 0.67945 -0.305054)
			(end 0.12065 -0.305054)
			(stroke
				(width 0.1)
				(type default)
			)
			(layer "B.Fab")
		)
		(fp_line
			(start 0.12065 -0.305054)
			(end 0.12065 -0.2794)
			(stroke
				(width 0.1)
				(type default)
			)
			(layer "B.Fab")
		)
		(fp_line
			(start -0.12065 -0.3048)
			(end -0.67945 -0.3048)
			(stroke
				(width 0.1)
				(type default)
			)
			(layer "B.Fab")
		)
		(fp_line
			(start -0.67945 -0.3048)
			(end -0.67945 0.3048)
			(stroke
				(width 0.1)
				(type default)
			)
			(layer "B.Fab")
		)
		(fp_line
			(start 0.12065 -0.2794)
			(end -0.12065 -0.2794)
			(stroke
				(width 0.1)
				(type default)
			)
			(layer "B.Fab")
		)
		(fp_line
			(start -0.12065 -0.2794)
			(end -0.12065 -0.3048)
			(stroke
				(width 0.1)
				(type default)
			)
			(layer "B.Fab")
		)
		(fp_line
			(start 0.12065 0.2794)
			(end 0.12065 0.3048)
			(stroke
				(width 0.1)
				(type default)
			)
			(layer "B.Fab")
		)
		(fp_line
			(start -0.120396 0.2794)
			(end 0.12065 0.2794)
			(stroke
				(width 0.1)
				(type default)
			)
			(layer "B.Fab")
		)
		(fp_line
			(start 0.67945 0.3048)
			(end 0.67945 -0.305054)
			(stroke
				(width 0.1)
				(type default)
			)
			(layer "B.Fab")
		)
		(fp_line
			(start 0.12065 0.3048)
			(end 0.67945 0.3048)
			(stroke
				(width 0.1)
				(type default)
			)
			(layer "B.Fab")
		)
		(fp_line
			(start -0.120396 0.3048)
			(end -0.120396 0.2794)
			(stroke
				(width 0.1)
				(type default)
			)
			(layer "B.Fab")
		)
		(fp_line
			(start -0.67945 0.3048)
			(end -0.120396 0.3048)
			(stroke
				(width 0.1)
				(type default)
			)
			(layer "B.Fab")
		)
		(pad "1" smd circle
			(at 0.40005 0 270)
			(size 0 0)
			(layers "B.Cu" "B.Mask" "B.Paste")
			(net "SMB_CPU0_SEC_R_SDA")
		)
		(pad "2" smd circle
			(at -0.40005 0 270)
			(size 0 0)
			(layers "B.Cu" "B.Mask" "B.Paste")
			(net "SMB_CPU0_SEC_SDA")
		)
	)
	(footprint ""
		(layer "B.Cu")
		(at 381.552958 -208.530952 -90)
		(property "Reference" "R399"
			(at 0 0 90)
			(layer "B.SilkS")
			(hide yes)
			(effects
				(font
					(size 1.27 1.27)
				)
				(justify mirror)
			)
		)
		(property "Value" ""
			(at 0 0 90)
			(layer "B.Fab")
			(effects
				(font
					(size 1.27 1.27)
				)
				(justify mirror)
			)
		)
		(duplicate_pad_numbers_are_jumpers no)
		(fp_line
			(start -0.7874 0.4064)
			(end 0.7874 0.4064)
			(stroke
				(width 0.1524)
				(type default)
			)
			(layer "B.SilkS")
		)
		(fp_line
			(start 0.7874 0.4064)
			(end 0.7874 -0.4064)
			(stroke
				(width 0.1524)
				(type default)
			)
			(layer "B.SilkS")
		)
		(fp_line
			(start -0.7874 -0.4064)
			(end -0.7874 0.4064)
			(stroke
				(width 0.1524)
				(type default)
			)
			(layer "B.SilkS")
		)
		(fp_line
			(start 0.7874 -0.4064)
			(end -0.7874 -0.4064)
			(stroke
				(width 0.1524)
				(type default)
			)
			(layer "B.SilkS")
		)
		(fp_line
			(start -0.67945 0.3048)
			(end -0.120396 0.3048)
			(stroke
				(width 0.1)
				(type default)
			)
			(layer "B.Fab")
		)
		(fp_line
			(start -0.120396 0.3048)
			(end -0.120396 0.2794)
			(stroke
				(width 0.1)
				(type default)
			)
			(layer "B.Fab")
		)
		(fp_line
			(start 0.12065 0.3048)
			(end 0.67945 0.3048)
			(stroke
				(width 0.1)
				(type default)
			)
			(layer "B.Fab")
		)
		(fp_line
			(start 0.67945 0.3048)
			(end 0.67945 -0.305054)
			(stroke
				(width 0.1)
				(type default)
			)
			(layer "B.Fab")
		)
		(fp_line
			(start -0.120396 0.2794)
			(end 0.12065 0.2794)
			(stroke
				(width 0.1)
				(type default)
			)
			(layer "B.Fab")
		)
		(fp_line
			(start 0.12065 0.2794)
			(end 0.12065 0.3048)
			(stroke
				(width 0.1)
				(type default)
			)
			(layer "B.Fab")
		)
		(fp_line
			(start -0.12065 -0.2794)
			(end -0.12065 -0.3048)
			(stroke
				(width 0.1)
				(type default)
			)
			(layer "B.Fab")
		)
		(fp_line
			(start 0.12065 -0.2794)
			(end -0.12065 -0.2794)
			(stroke
				(width 0.1)
				(type default)
			)
			(layer "B.Fab")
		)
		(fp_line
			(start -0.67945 -0.3048)
			(end -0.67945 0.3048)
			(stroke
				(width 0.1)
				(type default)
			)
			(layer "B.Fab")
		)
		(fp_line
			(start -0.12065 -0.3048)
			(end -0.67945 -0.3048)
			(stroke
				(width 0.1)
				(type default)
			)
			(layer "B.Fab")
		)
		(fp_line
			(start 0.12065 -0.305054)
			(end 0.12065 -0.2794)
			(stroke
				(width 0.1)
				(type default)
			)
			(layer "B.Fab")
		)
		(fp_line
			(start 0.67945 -0.305054)
			(end 0.12065 -0.305054)
			(stroke
				(width 0.1)
				(type default)
			)
			(layer "B.Fab")
		)
		(pad "1" smd circle
			(at 0.40005 0 90)
			(size 0 0)
			(layers "B.Cu" "B.Mask" "B.Paste")
			(net "PVDD18_S5_P0")
		)
		(pad "2" smd circle
			(at -0.40005 0 90)
			(size 0 0)
			(layers "B.Cu" "B.Mask" "B.Paste")
			(net "JTAG_CPU0_TDI")
		)
	)
	(footprint ""
		(layer "B.Cu")
		(at 46.308518 -350.660716 -90)
		(property "Reference" "PC446_2"
			(at 0 0 90)
			(layer "B.SilkS")
			(hide yes)
			(effects
				(font
					(size 1.27 1.27)
				)
				(justify mirror)
			)
		)
		(property "Value" ""
			(at 0 0 90)
			(layer "B.Fab")
			(effects
				(font
					(size 1.27 1.27)
				)
				(justify mirror)
			)
		)
		(duplicate_pad_numbers_are_jumpers no)
		(fp_line
			(start -1.524 0.762)
			(end 1.524 0.762)
			(stroke
				(width 0.1524)
				(type default)
			)
			(layer "B.SilkS")
		)
		(fp_line
			(start 1.524 0.762)
			(end 1.524 -0.762)
			(stroke
				(width 0.1524)
				(type default)
			)
			(layer "B.SilkS")
		)
		(fp_line
			(start -1.524 -0.762)
			(end -1.524 0.762)
			(stroke
				(width 0.1524)
				(type default)
			)
			(layer "B.SilkS")
		)
		(fp_line
			(start 1.524 -0.762)
			(end -1.524 -0.762)
			(stroke
				(width 0.1524)
				(type default)
			)
			(layer "B.SilkS")
		)
		(fp_line
			(start -1.1049 0.724916)
			(end -1.1049 -0.724916)
			(stroke
				(width 0.1)
				(type default)
			)
			(layer "B.Fab")
		)
		(fp_line
			(start 1.1049 0.724916)
			(end -1.1049 0.724916)
			(stroke
				(width 0.1)
				(type default)
			)
			(layer "B.Fab")
		)
		(fp_line
			(start -1.1049 -0.724916)
			(end 1.1049 -0.724916)
			(stroke
				(width 0.1)
				(type default)
			)
			(layer "B.Fab")
		)
		(fp_line
			(start 1.1049 -0.724916)
			(end 1.1049 0.724916)
			(stroke
				(width 0.1)
				(type default)
			)
			(layer "B.Fab")
		)
		(pad "1" smd rect
			(at 0.889 0 270)
			(size 1.016 1.27)
			(layers "B.Cu" "B.Mask" "B.Paste")
			(net "SW_P12V_AUX_PVDDIO_P1_FLT")
		)
		(pad "2" smd rect
			(at -0.889 0 270)
			(size 1.016 1.27)
			(layers "B.Cu" "B.Mask" "B.Paste")
			(net "GND")
		)
	)
	(footprint ""
		(layer "B.Cu")
		(at 315.518292 -396.393162 -90)
		(property "Reference" "C524"
			(at 0 0 90)
			(layer "B.SilkS")
			(hide yes)
			(effects
				(font
					(size 1.27 1.27)
				)
				(justify mirror)
			)
		)
		(property "Value" ""
			(at 0 0 90)
			(layer "B.Fab")
			(effects
				(font
					(size 1.27 1.27)
				)
				(justify mirror)
			)
		)
		(duplicate_pad_numbers_are_jumpers no)
		(fp_line
			(start -0.299974 0.150114)
			(end 0.299974 0.150114)
			(stroke
				(width 0.1)
				(type default)
			)
			(layer "B.Fab")
		)
		(fp_line
			(start 0.299974 0.150114)
			(end 0.299974 -0.150114)
			(stroke
				(width 0.1)
				(type default)
			)
			(layer "B.Fab")
		)
		(fp_line
			(start -0.299974 -0.150114)
			(end -0.299974 0.150114)
			(stroke
				(width 0.1)
				(type default)
			)
			(layer "B.Fab")
		)
		(fp_line
			(start 0.299974 -0.150114)
			(end -0.299974 -0.150114)
			(stroke
				(width 0.1)
				(type default)
			)
			(layer "B.Fab")
		)
		(pad "1" smd rect
			(at 0.2667 0 90)
			(size 0.3048 0.381)
			(layers "B.Cu" "B.Mask" "B.Paste")
			(net "P0V9_CPU0_RT_2D")
		)
		(pad "2" smd rect
			(at -0.2667 0 90)
			(size 0.3048 0.381)
			(layers "B.Cu" "B.Mask" "B.Paste")
			(net "GND")
		)
	)
)
